# S9S_MB_2U (Grand Teton) — schematic netlist excerpt (pin names and nets, part order shuffled) for the footprints in the layout excerpt that follows; sources: Cadence DE-HDL packaged netlist, KiCad conversion of 03242023_DA0F0TMBIJ0_F0T_Motherboard_J_brd_V01_OCP.brd

PR1133  Q_RES  2K 0.1% CHIP  pkg 0402LF  page 301 : A = HSC_IMON ; B = AGND_HSC
C611  Q_CAP  1UF 25V 10% X6S  pkg C0402  page 185 : A = P3V3_RTC_AUX ; B = GND
PL6  Q_INDUCTOR  100NH/16A IND  pkg SMLF  page 275 : \1\ = P12V_AUX ; \2\ = SW_P12V_PVCCINFAON_CPU0_FLT

(kicad_pcb
	(version 20260206)
	(generator "pcbnew")
	(generator_version "10.0")
	(general
		(thickness 1.6)
		(legacy_teardrops no)
	)
	(paper "A4")
	(title_block
		(title "03242023_DA0F0TMBIJ0_F0T_Motherboard_J_brd_V01_OCP.brd")
		(comment 1 "Grand Teton / footprints 3355-3357 of 6105")
	)
	(layers
		(0 "F.Cu" signal "TOP")
		(4 "In1.Cu" signal "GND")
		(6 "In2.Cu" signal "IN1")
		(8 "In3.Cu" signal "GND1")
		(10 "In4.Cu" signal "IN2")
		(12 "In5.Cu" signal "GND2")
		(14 "In6.Cu" signal "IN3")
		(16 "In7.Cu" signal "GND3")
		(18 "In8.Cu" signal "VCC")
		(20 "In9.Cu" signal "VCC1")
		(22 "In10.Cu" signal "GND4")
		(24 "In11.Cu" signal "IN4")
		(26 "In12.Cu" signal "GND5")
		(28 "In13.Cu" signal "IN5")
		(30 "In14.Cu" signal "GND6")
		(32 "In15.Cu" signal "IN6")
		(34 "In16.Cu" signal "GND7")
		(2 "B.Cu" signal "BOTTOM")
		(9 "F.Adhes" user "F.Adhesive")
		(11 "B.Adhes" user "B.Adhesive")
		(13 "F.Paste" user "Package Geometry/Pastemask Top")
		(15 "B.Paste" user "Package Geometry/Pastemask Bottom")
		(5 "F.SilkS" user "Ref Des/Silkscreen Top")
		(7 "B.SilkS" user "Ref Des/Silkscreen Bottom")
		(1 "F.Mask" user "Board Geometry/Soldermask Top")
		(3 "B.Mask" user "Board Geometry/Soldermask Bottom")
		(17 "Dwgs.User" user "User.Drawings")
		(19 "Cmts.User" user "User.Comments")
		(21 "Eco1.User" user "User.Eco1")
		(23 "Eco2.User" user "User.Eco2")
		(25 "Edge.Cuts" user "Board Geometry/Outline")
		(27 "Margin" user)
		(31 "F.CrtYd" user "Package Geometry/Place Bound Top")
		(29 "B.CrtYd" user "Package Geometry/Place Bound Bottom")
		(35 "F.Fab" user "Ref Des/Assembly Top")
		(33 "B.Fab" user "Ref Des/Assembly Bottom")
	)
	(footprint ""
		(layer "F.Cu")
		(at 303.523904 -32.462216)
		(property "Reference" "C611"
			(at 0 0 0)
			(layer "F.SilkS")
			(hide yes)
			(effects
				(font
					(size 1.27 1.27)
				)
			)
		)
		(property "Value" ""
			(at 0 0 0)
			(layer "F.Fab")
			(effects
				(font
					(size 1.27 1.27)
				)
			)
		)
		(duplicate_pad_numbers_are_jumpers no)
		(fp_line
			(start -0.7874 -0.4064)
			(end 0.7874 -0.4064)
			(stroke
				(width 0.1524)
				(type default)
			)
			(layer "F.SilkS")
		)
		(fp_line
			(start -0.7874 0.4064)
			(end -0.7874 -0.4064)
			(stroke
				(width 0.1524)
				(type default)
			)
			(layer "F.SilkS")
		)
		(fp_line
			(start 0.7874 -0.4064)
			(end 0.7874 0.4064)
			(stroke
				(width 0.1524)
				(type default)
			)
			(layer "F.SilkS")
		)
		(fp_line
			(start 0.7874 0.4064)
			(end -0.7874 0.4064)
			(stroke
				(width 0.1524)
				(type default)
			)
			(layer "F.SilkS")
		)
		(fp_line
			(start -0.67945 -0.305054)
			(end -0.12065 -0.305054)
			(stroke
				(width 0.1)
				(type default)
			)
			(layer "F.Fab")
		)
		(fp_line
			(start -0.67945 0.3048)
			(end -0.67945 -0.305054)
			(stroke
				(width 0.1)
				(type default)
			)
			(layer "F.Fab")
		)
		(fp_line
			(start -0.12065 -0.305054)
			(end -0.12065 -0.2794)
			(stroke
				(width 0.1)
				(type default)
			)
			(layer "F.Fab")
		)
		(fp_line
			(start -0.12065 -0.2794)
			(end 0.12065 -0.2794)
			(stroke
				(width 0.1)
				(type default)
			)
			(layer "F.Fab")
		)
		(fp_line
			(start -0.12065 0.2794)
			(end -0.12065 0.3048)
			(stroke
				(width 0.1)
				(type default)
			)
			(layer "F.Fab")
		)
		(fp_line
			(start -0.12065 0.3048)
			(end -0.67945 0.3048)
			(stroke
				(width 0.1)
				(type default)
			)
			(layer "F.Fab")
		)
		(fp_line
			(start 0.120396 0.2794)
			(end -0.12065 0.2794)
			(stroke
				(width 0.1)
				(type default)
			)
			(layer "F.Fab")
		)
		(fp_line
			(start 0.120396 0.3048)
			(end 0.120396 0.2794)
			(stroke
				(width 0.1)
				(type default)
			)
			(layer "F.Fab")
		)
		(fp_line
			(start 0.12065 -0.3048)
			(end 0.67945 -0.3048)
			(stroke
				(width 0.1)
				(type default)
			)
			(layer "F.Fab")
		)
		(fp_line
			(start 0.12065 -0.2794)
			(end 0.12065 -0.3048)
			(stroke
				(width 0.1)
				(type default)
			)
			(layer "F.Fab")
		)
		(fp_line
			(start 0.67945 -0.3048)
			(end 0.67945 0.3048)
			(stroke
				(width 0.1)
				(type default)
			)
			(layer "F.Fab")
		)
		(fp_line
			(start 0.67945 0.3048)
			(end 0.120396 0.3048)
			(stroke
				(width 0.1)
				(type default)
			)
			(layer "F.Fab")
		)
		(pad "1" smd circle
			(at -0.40005 0)
			(size 0 0)
			(layers "F.Cu" "F.Mask" "F.Paste")
			(net "P3V3_RTC_AUX")
		)
		(pad "2" smd circle
			(at 0.40005 0)
			(size 0 0)
			(layers "F.Cu" "F.Mask" "F.Paste")
			(net "GND")
		)
	)
	(footprint ""
		(layer "F.Cu")
		(at 429.272192 -164.780722 180)
		(property "Reference" "PL6"
			(at -2.44094 3.725164 0)
			(unlocked yes)
			(layer "F.SilkS")
			(effects
				(font
					(size 0.7874 0.5842)
					(thickness 0.1524)
				)
				(justify left)
			)
		)
		(property "Value" ""
			(at 0 0 180)
			(layer "F.Fab")
			(effects
				(font
					(size 1.27 1.27)
				)
			)
		)
		(duplicate_pad_numbers_are_jumpers no)
		(fp_line
			(start 2.249932 2.249932)
			(end -2.249932 2.249932)
			(stroke
				(width 0.1524)
				(type default)
			)
			(layer "F.SilkS")
		)
		(fp_line
			(start 2.249932 1.3843)
			(end 2.249932 2.249932)
			(stroke
				(width 0.1524)
				(type default)
			)
			(layer "F.SilkS")
		)
		(fp_line
			(start 2.249932 -2.249932)
			(end 2.249932 -1.3843)
			(stroke
				(width 0.1524)
				(type default)
			)
			(layer "F.SilkS")
		)
		(fp_line
			(start -2.249932 2.249932)
			(end -2.249932 1.3843)
			(stroke
				(width 0.1524)
				(type default)
			)
			(layer "F.SilkS")
		)
		(fp_line
			(start -2.249932 -1.3843)
			(end -2.249932 -2.249932)
			(stroke
				(width 0.1524)
				(type default)
			)
			(layer "F.SilkS")
		)
		(fp_line
			(start -2.249932 -2.249932)
			(end 2.249932 -2.249932)
			(stroke
				(width 0.1524)
				(type default)
			)
			(layer "F.SilkS")
		)
		(fp_line
			(start 2.249932 2.249932)
			(end -2.249932 2.249932)
			(stroke
				(width 0.1)
				(type default)
			)
			(layer "F.Fab")
		)
		(fp_line
			(start 2.249932 -2.249932)
			(end 2.249932 2.249932)
			(stroke
				(width 0.1)
				(type default)
			)
			(layer "F.Fab")
		)
		(fp_line
			(start -2.249932 2.249932)
			(end -2.249932 -2.249932)
			(stroke
				(width 0.1)
				(type default)
			)
			(layer "F.Fab")
		)
		(fp_line
			(start -2.249932 -2.249932)
			(end 2.249932 -2.249932)
			(stroke
				(width 0.1)
				(type default)
			)
			(layer "F.Fab")
		)
		(pad "1" smd rect
			(at -1.82499 0 180)
			(size 1.0668 2.5146)
			(layers "F.Cu" "F.Mask" "F.Paste")
			(net "P12V_AUX")
		)
		(pad "2" smd rect
			(at 1.82499 0 180)
			(size 1.0668 2.5146)
			(layers "F.Cu" "F.Mask" "F.Paste")
			(net "SW_P12V_PVCCINFAON_CPU0_FLT")
		)
	)
	(footprint ""
		(layer "F.Cu")
		(at 179.352448 -399.207482 180)
		(property "Reference" "PR1133"
			(at 0 0 180)
			(layer "F.SilkS")
			(hide yes)
			(effects
				(font
					(size 1.27 1.27)
				)
			)
		)
		(property "Value" ""
			(at 0 0 180)
			(layer "F.Fab")
			(effects
				(font
					(size 1.27 1.27)
				)
			)
		)
		(duplicate_pad_numbers_are_jumpers no)
		(fp_line
			(start 0.7874 0.4064)
			(end -0.7874 0.4064)
			(stroke
				(width 0.1524)
				(type default)
			)
			(layer "F.SilkS")
		)
		(fp_line
			(start 0.7874 -0.4064)
			(end 0.7874 0.4064)
			(stroke
				(width 0.1524)
				(type default)
			)
			(layer "F.SilkS")
		)
		(fp_line
			(start -0.7874 0.4064)
			(end -0.7874 -0.4064)
			(stroke
				(width 0.1524)
				(type default)
			)
			(layer "F.SilkS")
		)
		(fp_line
			(start -0.7874 -0.4064)
			(end 0.7874 -0.4064)
			(stroke
				(width 0.1524)
				(type default)
			)
			(layer "F.SilkS")
		)
		(fp_line
			(start 0.67945 0.3048)
			(end 0.120396 0.3048)
			(stroke
				(width 0.1)
				(type default)
			)
			(layer "F.Fab")
		)
		(fp_line
			(start 0.67945 -0.3048)
			(end 0.67945 0.3048)
			(stroke
				(width 0.1)
				(type default)
			)
			(layer "F.Fab")
		)
		(fp_line
			(start 0.12065 -0.2794)
			(end 0.12065 -0.3048)
			(stroke
				(width 0.1)
				(type default)
			)
			(layer "F.Fab")
		)
		(fp_line
			(start 0.12065 -0.3048)
			(end 0.67945 -0.3048)
			(stroke
				(width 0.1)
				(type default)
			)
			(layer "F.Fab")
		)
		(fp_line
			(start 0.120396 0.3048)
			(end 0.120396 0.2794)
			(stroke
				(width 0.1)
				(type default)
			)
			(layer "F.Fab")
		)
		(fp_line
			(start 0.120396 0.2794)
			(end -0.12065 0.2794)
			(stroke
				(width 0.1)
				(type default)
			)
			(layer "F.Fab")
		)
		(fp_line
			(start -0.12065 0.3048)
			(end -0.67945 0.3048)
			(stroke
				(width 0.1)
				(type default)
			)
			(layer "F.Fab")
		)
		(fp_line
			(start -0.12065 0.2794)
			(end -0.12065 0.3048)
			(stroke
				(width 0.1)
				(type default)
			)
			(layer "F.Fab")
		)
		(fp_line
			(start -0.12065 -0.2794)
			(end 0.12065 -0.2794)
			(stroke
				(width 0.1)
				(type default)
			)
			(layer "F.Fab")
		)
		(fp_line
			(start -0.12065 -0.305054)
			(end -0.12065 -0.2794)
			(stroke
				(width 0.1)
				(type default)
			)
			(layer "F.Fab")
		)
		(fp_line
			(start -0.67945 0.3048)
			(end -0.67945 -0.305054)
			(stroke
				(width 0.1)
				(type default)
			)
			(layer "F.Fab")
		)
		(fp_line
			(start -0.67945 -0.305054)
			(end -0.12065 -0.305054)
			(stroke
				(width 0.1)
				(type default)
			)
			(layer "F.Fab")
		)
		(pad "1" smd circle
			(at -0.40005 0 180)
			(size 0 0)
			(layers "F.Cu" "F.Mask" "F.Paste")
			(net "HSC_IMON")
		)
		(pad "2" smd circle
			(at 0.40005 0 180)
			(size 0 0)
			(layers "F.Cu" "F.Mask" "F.Paste")
			(net "AGND_HSC")
		)
	)
)
